# BASEBOARD_FAB2 (Tioga Pass) — schematic netlist excerpt (pin names and nets, part order shuffled) for the footprints in the layout excerpt that follows; sources: Cadence DE-HDL packaged netlist, KiCad conversion of Wiwynn_Tioga_Pass_MB.brd

C8C13  CAP_A  0.1UF 16V 10% X7R  pkg 0402V  page 188 : A = KR_P1_OCP_RX_DN ; B = KR_P1_OCP_RX_C_DN
C5G4  CAP_A  47UF 4V 20% X5R  pkg 0603V  page 217 : A = PVDDQ_ABC ; B = GND
C1C4  CAP  0.22UF 16V 10% X7R  pkg 0402  page 210 : A = P5V_STBY ; B = GND

(kicad_pcb
	(version 20260206)
	(generator "pcbnew")
	(generator_version "10.0")
	(general
		(thickness 1.6)
		(legacy_teardrops no)
	)
	(paper "A4")
	(title_block
		(title "Wiwynn_Tioga_Pass_MB.brd")
		(comment 1 "Tioga Pass / footprints 1843-1845 of 4770")
	)
	(layers
		(0 "F.Cu" signal "TOP")
		(4 "In1.Cu" signal "L2GND")
		(6 "In2.Cu" signal "L3")
		(8 "In3.Cu" signal "L4GND")
		(10 "In4.Cu" signal "L5")
		(12 "In5.Cu" signal "L6GND")
		(14 "In6.Cu" signal "L7VCC")
		(16 "In7.Cu" signal "L8VCC")
		(18 "In8.Cu" signal "L9GND")
		(20 "In9.Cu" signal "L10")
		(22 "In10.Cu" signal "L11GND")
		(24 "In11.Cu" signal "L12")
		(26 "In12.Cu" signal "L13GND")
		(2 "B.Cu" signal "BOTTOM")
		(9 "F.Adhes" user "F.Adhesive")
		(11 "B.Adhes" user "B.Adhesive")
		(13 "F.Paste" user "Package Geometry/Pastemask Top")
		(15 "B.Paste" user "Package Geometry/Pastemask Bottom")
		(5 "F.SilkS" user "Ref Des/Silkscreen Top")
		(7 "B.SilkS" user "Ref Des/Silkscreen Bottom")
		(1 "F.Mask" user "Board Geometry/Soldermask Top")
		(3 "B.Mask" user "Board Geometry/Soldermask Bottom")
		(17 "Dwgs.User" user "User.Drawings")
		(19 "Cmts.User" user "User.Comments")
		(21 "Eco1.User" user "User.Eco1")
		(23 "Eco2.User" user "User.Eco2")
		(25 "Edge.Cuts" user "Board Geometry/Outline")
		(27 "Margin" user)
		(31 "F.CrtYd" user "Package Geometry/Place Bound Top")
		(29 "B.CrtYd" user "Package Geometry/Place Bound Bottom")
		(35 "F.Fab" user "Ref Des/Assembly Top")
		(33 "B.Fab" user "Ref Des/Assembly Bottom")
	)
	(footprint ""
		(layer "F.Cu")
		(at 253.392432 -12.954 90)
		(property "Reference" "C5G4"
			(at 1.848866 0.752348 90)
			(unlocked yes)
			(layer "F.SilkS")
			(effects
				(font
					(size 1.27 0.9652)
					(thickness 0.1524)
				)
			)
		)
		(property "Value" ""
			(at 0 0 90)
			(layer "F.Fab")
			(effects
				(font
					(size 1.27 1.27)
				)
			)
		)
		(duplicate_pad_numbers_are_jumpers no)
		(fp_rect
			(start -0.500126 1.598422)
			(end 0.500126 -0.201422)
			(stroke
				(width 0)
				(type default)
			)
			(fill no)
			(layer "F.CrtYd")
		)
		(fp_line
			(start 0.500126 -0.201422)
			(end 0.500126 1.598422)
			(stroke
				(width 0.1)
				(type default)
			)
			(layer "F.Fab")
		)
		(fp_line
			(start -0.500126 -0.201422)
			(end 0.500126 -0.201422)
			(stroke
				(width 0.1)
				(type default)
			)
			(layer "F.Fab")
		)
		(fp_line
			(start 0.500126 1.598422)
			(end -0.500126 1.598422)
			(stroke
				(width 0.1)
				(type default)
			)
			(layer "F.Fab")
		)
		(fp_line
			(start -0.500126 1.598422)
			(end -0.500126 -0.201422)
			(stroke
				(width 0.1)
				(type default)
			)
			(layer "F.Fab")
		)
		(pad "1" smd rect
			(at 0 0)
			(size 0.889 0.9906)
			(layers "F.Cu" "F.Mask" "F.Paste")
			(net "PVDDQ_ABC")
		)
		(pad "2" smd rect
			(at 0 1.397)
			(size 0.889 0.9906)
			(layers "F.Cu" "F.Mask" "F.Paste")
			(net "GND")
		)
		(zone
			(layer "F.Cu")
			(hatch none 0.5)
			(connect_pads
				(clearance 0)
			)
			(min_thickness 0.25)
			(keepout
				(tracks allowed)
				(vias not_allowed)
				(pads allowed)
				(copperpour not_allowed)
				(footprints allowed)
			)
			(placement
				(enabled no)
				(sheetname "")
			)
			(fill
				(thermal_gap 0.5)
				(thermal_bridge_width 0.5)
				(island_removal_mode 0)
			)
			(polygon
				(pts
					(xy 254.344932 -12.4587) (xy 254.344932 -13.4493) (xy 253.836932 -13.4493) (xy 253.836932 -12.4587)
				)
			)
		)
		(zone
			(layer "F.Cu")
			(hatch none 0.5)
			(connect_pads
				(clearance 0)
			)
			(min_thickness 0.25)
			(keepout
				(tracks not_allowed)
				(vias allowed)
				(pads allowed)
				(copperpour not_allowed)
				(footprints allowed)
			)
			(placement
				(enabled no)
				(sheetname "")
			)
			(fill
				(thermal_gap 0.5)
				(thermal_bridge_width 0.5)
				(island_removal_mode 0)
			)
			(polygon
				(pts
					(xy 254.344932 -12.4587) (xy 254.344932 -13.4493) (xy 253.836932 -13.4493) (xy 253.836932 -12.4587)
				)
			)
		)
	)
	(footprint ""
		(layer "F.Cu")
		(at 407.753566 -95.687642 -90)
		(property "Reference" "C8C13"
			(at -0.8382 -0.67818 270)
			(unlocked yes)
			(layer "F.SilkS")
			(effects
				(font
					(size 0.4064 0.254)
					(thickness 0.1524)
				)
				(justify left)
			)
		)
		(property "Value" ""
			(at 0 0 270)
			(layer "F.Fab")
			(effects
				(font
					(size 1.27 1.27)
				)
			)
		)
		(duplicate_pad_numbers_are_jumpers no)
		(fp_poly
			(pts
				(xy 0.3048 -0.1016) (xy 0.3048 0.9906) (xy -0.3048 0.9906) (xy -0.3048 -0.1016)
			)
			(stroke
				(width 0)
				(type default)
			)
			(fill no)
			(layer "F.CrtYd")
		)
		(fp_line
			(start -0.3048 0.9906)
			(end 0.3048 0.9906)
			(stroke
				(width 0.1)
				(type default)
			)
			(layer "F.Fab")
		)
		(fp_line
			(start 0.3048 0.9906)
			(end 0.3048 -0.1016)
			(stroke
				(width 0.1)
				(type default)
			)
			(layer "F.Fab")
		)
		(fp_line
			(start -0.3048 -0.1016)
			(end -0.3048 0.9906)
			(stroke
				(width 0.1)
				(type default)
			)
			(layer "F.Fab")
		)
		(fp_line
			(start 0.3048 -0.1016)
			(end -0.3048 -0.1016)
			(stroke
				(width 0.1)
				(type default)
			)
			(layer "F.Fab")
		)
		(pad "1" smd rect
			(at 0 0 270)
			(size 0.508 0.508)
			(layers "F.Cu" "F.Mask" "F.Paste")
			(net "KR_P1_OCP_RX_DN")
		)
		(pad "2" smd rect
			(at 0 0.889 270)
			(size 0.508 0.508)
			(layers "F.Cu" "F.Mask" "F.Paste")
			(net "KR_P1_OCP_RX_C_DN")
		)
		(zone
			(layer "F.Cu")
			(hatch none 0.5)
			(connect_pads
				(clearance 0)
			)
			(min_thickness 0.25)
			(keepout
				(tracks not_allowed)
				(vias allowed)
				(pads allowed)
				(copperpour not_allowed)
				(footprints allowed)
			)
			(placement
				(enabled no)
				(sheetname "")
			)
			(fill
				(thermal_gap 0.5)
				(thermal_bridge_width 0.5)
				(island_removal_mode 0)
			)
			(polygon
				(pts
					(xy 407.118566 -95.941642) (xy 407.118566 -95.433642) (xy 407.499566 -95.433642) (xy 407.499566 -95.941642)
				)
			)
		)
		(zone
			(layer "F.Cu")
			(hatch none 0.5)
			(connect_pads
				(clearance 0)
			)
			(min_thickness 0.25)
			(keepout
				(tracks allowed)
				(vias not_allowed)
				(pads allowed)
				(copperpour not_allowed)
				(footprints allowed)
			)
			(placement
				(enabled no)
				(sheetname "")
			)
			(fill
				(thermal_gap 0.5)
				(thermal_bridge_width 0.5)
				(island_removal_mode 0)
			)
			(polygon
				(pts
					(xy 407.499566 -95.941642) (xy 407.499566 -95.433642) (xy 407.118566 -95.433642) (xy 407.118566 -95.941642)
				)
			)
		)
	)
	(footprint ""
		(layer "F.Cu")
		(at 33.240726 -93.787214 90)
		(property "Reference" "C1C4"
			(at 0 0 90)
			(layer "F.SilkS")
			(hide yes)
			(effects
				(font
					(size 1.27 1.27)
				)
			)
		)
		(property "Value" ""
			(at 0 0 90)
			(layer "F.Fab")
			(effects
				(font
					(size 1.27 1.27)
				)
			)
		)
		(duplicate_pad_numbers_are_jumpers no)
		(fp_rect
			(start 0.3048 0.9906)
			(end -0.3048 -0.1016)
			(stroke
				(width 0)
				(type default)
			)
			(fill no)
			(layer "F.CrtYd")
		)
		(fp_line
			(start 0.3048 -0.1016)
			(end -0.3048 -0.1016)
			(stroke
				(width 0.1)
				(type default)
			)
			(layer "F.Fab")
		)
		(fp_line
			(start -0.3048 -0.1016)
			(end -0.3048 0.9906)
			(stroke
				(width 0.1)
				(type default)
			)
			(layer "F.Fab")
		)
		(fp_line
			(start 0.3048 0.9906)
			(end 0.3048 -0.1016)
			(stroke
				(width 0.1)
				(type default)
			)
			(layer "F.Fab")
		)
		(fp_line
			(start -0.3048 0.9906)
			(end 0.3048 0.9906)
			(stroke
				(width 0.1)
				(type default)
			)
			(layer "F.Fab")
		)
		(pad "1" smd rect
			(at 0 0 90)
			(size 0.508 0.508)
			(layers "F.Cu" "F.Mask" "F.Paste")
			(net "P5V_STBY")
		)
		(pad "2" smd rect
			(at 0 0.889 90)
			(size 0.508 0.508)
			(layers "F.Cu" "F.Mask" "F.Paste")
			(net "GND")
		)
		(zone
			(layer "F.Cu")
			(hatch none 0.5)
			(connect_pads
				(clearance 0)
			)
			(min_thickness 0.25)
			(keepout
				(tracks allowed)
				(vias not_allowed)
				(pads allowed)
				(copperpour not_allowed)
				(footprints allowed)
			)
			(placement
				(enabled no)
				(sheetname "")
			)
			(fill
				(thermal_gap 0.5)
				(thermal_bridge_width 0.5)
				(island_removal_mode 0)
			)
			(polygon
				(pts
					(xy 33.875726 -94.041214) (xy 33.494726 -94.041214) (xy 33.494726 -93.533214) (xy 33.875726 -93.533214)
				)
			)
		)
		(zone
			(layer "F.Cu")
			(hatch none 0.5)
			(connect_pads
				(clearance 0)
			)
			(min_thickness 0.25)
			(keepout
				(tracks not_allowed)
				(vias allowed)
				(pads allowed)
				(copperpour not_allowed)
				(footprints allowed)
			)
			(placement
				(enabled no)
				(sheetname "")
			)
			(fill
				(thermal_gap 0.5)
				(thermal_bridge_width 0.5)
				(island_removal_mode 0)
			)
			(polygon
				(pts
					(xy 33.875726 -94.041214) (xy 33.494726 -94.041214) (xy 33.494726 -93.533214) (xy 33.875726 -93.533214)
				)
			)
		)
	)
)
